# BASEBOARD_FAB2 (Tioga Pass) — schematic parts with pin connectivity, parts 4718–4718 of 4751; source: Cadence DE-HDL packaged netlist (pstxprt.dat, pstxnet.dat, pstchip.dat)

U25W4  AST2520A1-GP-GP  pkg ASIC2-GB1  page 143  (pins 1-306 of 456)
  A1  GND0  POWER  = GND
  A2  RGMII2TXD0_RMII2TXD0_GPIOU0  OUT  = RMII_BMC_PCH_SPRNGVLLE_TXD0_R
  A3  RGMII1RXD0_RMII1RXD0_GPIOU6  BI  = RMII_BMC_OCP_RXD0
  A4  RGMII1RXCTL_GPIOU5  BI  = FM_BMC_FAULT_LED_N
  A5  RGMII1TXD1_RMII1TXD1_GPIOT3  OUT  = RMII_BMC_OCP_TXD1_R
  A6  USB2B_DN  BI  = USB2_PCH_BMC_P5_DN
  A7  USB2A_DP  BI  = USB_PCH_BMC_P4_DP
  A8  USB2A_DN  BI  = USB_PCH_BMC_P4_DN
  A9  GPIOQ2_SCL4  BI  = SMB_HOST_STBY_LVC3_SCL_R
  A10  GPIOQ1_SDA3  BI  = SMB_OCP_LAN_STBY_LVC3_SDA_R
  A11  GPIOQ0_SCL3  BI  = SMB_OCP_LAN_STBY_LVC3_SCL_R
  A12  GPIOC1_SD1CMD_SDA10  BI  = SMB_DEBUG_STBY_LVC3_SDA_R
  A13  GPIOA5_TIMER6_SDA9  BI  = SMB_OCP_FRU_STBY_LVC3_SDA_R
  A14  GPIOI6_SPI1MOSI_VBMOSI  BI  = SPI_BMC_DO
  A15  GPIOI7_SPI1MISO_VBMISO  BI  = SPI_BMC_DI
  A16  GPIOH6_TXD6  BI  = LED_POSTCODE_6
  A17  GPIOH4_NDTR6  BI  = LED_POSTCODE_4
  A18  GPIOH0_NCTS6  BI  = LED_POSTCODE_0
  A19  GPIOG0_SGPS1CK  BI  = FM_CPU_ERR2_LVT3_N
  A20  GPIOE6_TXD3  BI  = FM_CPU0_PROCHOT_LVT3_BMC_N
  A21  GPIOF4_NDTR4_LHCLK  BI  = IRQ_PVDDQ_KLM_VRHOT_LVT3_N
  A22  GND1  POWER  = GND
  AA1  GPIOM2_NDSR2_VPIB4  BI  = IRQ_BOARD_BMC_ALERT_N
  AA2  GPIOM4_NDTR2_VPIB6  BI  = FM_CPU0_THERMTRIP_LATCH_LVT3_N
  AA3  GPION5_PWM5_VPIG5  BI  = FM_BIOS_SPI_BMC_CTRL
  AA4  GPIOO6_TACH6_VPIR4  BI  = FM_XRC_PRESENT_N
  AA5  GPIOP2_TACH10_VPIR8  BI  = FM_BOARD_SKU_ID2
  AA6  MDQ12  BI  = BMC_M_DQ12
  AA7  GND5  POWER  = GND
  AA8  MDQ8  BI  = BMC_M_DQ8
  AA9  GND6  POWER  = GND
  AA10  MDQ3  BI  = BMC_M_DQ3
  AA11  GND2  POWER  = GND
  AA12  \mcs#\  OUT  = BMC_M_CS_N
  AA13  GND3  POWER  = GND
  AA14  MA11  OUT  = BMC_M_A11
  AA15  GND4  POWER  = GND
  AA16  MA7  OUT  = BMC_M_A7
  AA17  PECIVDD  POWER  = PVCCIO_CPU0_R
  AA18  FWSPICK  BI  = SPI_BMC_BT_CLK_R
  AA19  \gpior0_fwspics1#\  BI  = SPI_BMC_BT_CS_R_N
  AA20  GPIOS7_VPOB9  BI  = GPIOS7
  AA21  \gpioz3_vpog5_nora3_siosci#\  BI  = IRQ_BMC_PCH_SCI_LPC_N
  AA22  GPIOAA3_VPOR5_NORD3_SALT10  BI  = FM_TPM_PRES_N
  AB1  GND7  POWER  = GND
  AB2  GPIOM1_NDCD2_VPIB3  BI  = FM_CPU1_RC_ERROR_N
  AB3  GPIOO4_TACH4_VPIR2  BI  = PUMP_TACH0
  AB4  GPIOO3_TACH3  BI  = FAN_TACH3
  AB5  GPIOP3_TACH11_VPIR9  BI  = FM_BOARD_SKU_ID3
  AB6  MDQS1N  BI  = BMC_M_DQS1_DN
  AB7  MDQS1P  BI  = BMC_M_DQS1_DP
  AB8  MDM1  OUT  = BMC_M_DM1
  AB9  MDQS0P  BI  = BMC_M_DQS0_DP
  AB10  MDQS0N  BI  = BMC_M_DQS0_DN
  AB11  MCKP  OUT  = BMC_M_CLK_DP
  AB12  MCKN  OUT  = BMC_M_CLK_DN
  AB13  \mcas#\  OUT  = BMC_M_CAS_N
  AB14  MA1  OUT  = BMC_M_A1
  AB15  MA13  OUT  = BMC_M_A13
  AB16  MA6  OUT  = BMC_M_A6
  AB17  \mreset#\  OUT  = BMC_M_RST_N
  AB18  PECI  BI  = PECI_BMC_R
  AB19  \fwspics0#\  BI  = SPI_BMC_BT_CS0_N
  AB20  GPIOZ1_VPOG3_NORA1_SIOPWRGD  BI  = FM_BMC_NMI_N_R
  AB21  \gpioz2_vpog4_nora2_siopbo#\  BI  = IRQ_PVDDQ_DEF_VRHOT_LVT3_N
  AB22  GND8  POWER  = GND
  B1  RGMII2TXCTL_RMII2TXEN_GPIOT7  OUT  = RMII_BMC_SPRNGVLLE_TXEN_R
  B2  RGMII2TXCK_RMII2RCLKO_GPIOT6  OUT  = NC
  B3  RGMII2TXD1_RMII2TXD1_GPIOU1  OUT  = RMII_BMC_PCH_SPRNGVLLE_TXD1_R
  B4  RGMII1RXCK_RMII1RCLKI_GPIOU4  BI  = CLK_50M_CKMNG_BMC_1
  B5  RGMII1TXCK_RMII1RCLKO_GPIOT0  OUT  = NC
  B6  USB2B_DP  BI  = USB2_PCH_BMC_P5_DP
  B7  USB2BVRES  UNSPEC  = A_USB2BVRES
  B8  USB2AVRES  UNSPEC  = A_USB2AVRES
  B9  GPIOQ3_SDA4  BI  = SMB_HOST_STBY_LVC3_SDA_R
  B10  GPIOQ6_OSCCLK  BI  = FM_POST_CARD_PRES_BMC_N
  B11  \gpioc7_sd1wp#_sda13\  BI  = SMB_PEHPCPU0_STBY_LVC3_R2_SDA
  B12  GPIOC2_SD1DAT0_SCL11  BI  = SMB_PEHPCPU0_STBY_LVC3_SCL
  B13  GPIOA7_TIMER8_MDIO2  BI  = FM_BMC_CPLD_MP_RST_N
  B14  GPIOA0_MAC1LINK  BI  = JTAG_RISER_N
  B15  \gpioi4_spi1cs0#_vbcs#\  BI  = SPI_BMC_CS0_N
  B16  GPIOI2_SYSMOSI  BI  = FM_FORCE_ADR_N
  B17  GPIOH5_NRTS6  BI  = LED_POSTCODE_5
  B18  GPIOH1_NDCD6  BI  = LED_POSTCODE_1
  B19  GPIOE7_RXD3  BI  = FM_CPU1_PROCHOT_LVT3_BMC_N
  B20  GPIOE0_NCTS3  BI  = RST_SYSTEM_BTN_R_N
  B21  GPIOF3_NRI4_LHAD3  BI  = IRQ_PVCCIN_CPU1_VRHOT_LVC3_N
  B22  GPIOF2_NDSR4_LHAD2  BI  = IRQ_PVCCIN_CPU0_VRHOT_LVC3_N
  C1  RGMII2RXCTL_GPIOV3  BI  = FM_FAST_PROCHOT_EN_N
  C2  RGMII2RXCK_RMII2RCLKI_GPIOV2  BI  = CLK_50M_CKMNG_BMC_2
  C3  RGMII2RXD0_RMII2RXD0_GPIOV4  BI  = RMII_SPRNGVLLE_BMC_PCH_RXD0
  C4  RGMII1RXD3_RMII1RXER_GPIOV1  BI  = RMII_BMC_OCP_RXER
  C5  RGMII1RXD2_RMII1CRSDV_GPIOV0  BI  = RMII_BMC_OCP_CRSDV
  C6  GND9  POWER  = GND
  C7  USB2AV33  POWER  = P3V3_USB2A_ALG
  C8  TMS  BI  = JTAG_BMC_TMS
  C9  RTCK  OUT  = PU_JTAG_BMC_RTCK
  C10  TCK  BI  = JTAG_BMC_TCK
  C11  \gpioc6_sd1cd#_scl13\  BI  = SMB_PEHPCPU0_STBY_LVC3_R2_SCL
  C12  GPIOC0_SD1CLK_SCL10  BI  = SMB_DEBUG_STBY_LVC3_SCL_R
  C13  GPIOA6_TIMER7_MDC2  BI  = FM_BB_BMC_MP_GPIO
  C14  GPIOA4_TIMER5_SCL9  BI  = SMB_OCP_FRU_STBY_LVC3_SCL_R
  C15  GPIOI5_SPI1CK_VBCK  BI  = SPI_BMC_CLK
  C16  GPIOI3_SYSMISO  BI  = FM_UV_ADR_TRIGGER_EN
  C17  GPIOH3_NRI6  BI  = LED_POSTCODE_3
  C18  \gpioi0_syscs#\  BI  = FM_CPU0_FIVR_FAULT_LVT3_R_N
  C19  GPIOG2_SGPS1I0  BI  = FM_PCH_BMC_THERMTRIP_N
  C20  GPIOE1_NDCD3  BI  = RST_BMC_SYSRST_BTN_OUT_N
  C21  \gpiod7_sd2wp#\  BI  = FM_CPU_ERR1_LVT3_BMC_N
  C22  GPIOAC4_ESPICK_LCLK  BI  = CLK_24M_BMC_LPC
  D1  RGMII2RXD1_RMII2RXD1_GPIOV5  BI  = RMII_SPRNGVLLE_BMC_PCH_RXD1
  D2  RGMII2RXD2_RMII2CRSDV_GPIOV6  BI  = RMII_BMC_PCH_SPRNGVLLE_CRSDV
  D3  RGMIICK  IN  = NC
  D4  RGMII2TXD3_GPIOU3  OUT  = TP_RGMII2TXD3_GPIOU3
  D5  RGMII2TXD2_GPIOU2  OUT  = TP_RGMII2TXD2_GPIOU2
  D6  RGMII1RXD1_RMII1RXD1_GPIOU7  BI  = RMII_BMC_OCP_RXD1
  D7  RGMII1TXD3_GPIOT5  OUT  = TP_RGMII1TXD3_GPIOT5
  D8  GPIOR6_MDC1  BI  = FM_SLT_CFG0
  D9  GPIOC3_SD1DAT1_SDA11  BI  = SMB_PEHPCPU0_STBY_LVC3_SDA
  D10  GPIOC4_SD1DAT2_SCL12  BI  = SMB_PEHPCPU1_STBY_LVC3_SCL
  D11  TDO  BI  = JTAG_BMC_TDO
  D12  TDI  BI  = JTAG_BMC_TDI
  D13  \gpioa2_timer3_spi1cs1#\  BI  = TP_BMC_GPIOA2
  D14  GPIOA1_MAC2LINK  BI  = FM_CPLD_BMC_PWRDN_N
  D15  GPIOG6_SGPS2I0_SALT3  BI  = IRQ_MEZZ_LAN_ALERT_N
  D16  GPIOG5_SGPS2LD_SALT2  BI  = IRQ_OOB_MGMT_RISER_ALERT_N
  D17  GPIOH2_NDSR6  BI  = LED_POSTCODE_2
  D18  GPIOH7_RXD6  BI  = LED_POSTCODE_7
  D19  GPIOE5_NRTS3  BI  = IRQ_BMC_PCH_NMI_STBY_N
  D20  GPIOD3_SD2DAT1  BI  = FM_BOARD_REV_ID1
  D21  GPIOD4_SD2DAT2  BI  = IRQ_DIMM_SAVE_LVT3_N
  D22  GPIOAC2_ESPID2_LAD2  BI  = LPC_LAD2_IO2_R
  E1  ADC3_GPIW3  IN  = A_P1V05_STBY_PCH_SENSOR
  E2  ADC2_GPIW2  IN  = A_P12V_STBY_SCALED
  E3  ADC5_GPIW5  IN  = A_P3V3_STBY_SCALED
  E4  BATVDD  POWER  = VCCBAT_TW12
  E5  GND68  POWER  = GND
  E6  RGMII2RXD3_RMII2RXER_GPIOV7  BI  = RMII_BMC_PCH_SPRNGVLLE_RXER
  E7  RGMII1TXD2_GPIOT4  OUT  = TP_RGMII1TXD2_GPIOT4
  E8  GND10  POWER  = GND
  E9  RGMII1TXCTL_RMII1TXEN_GPIOT1  OUT  = RMII_BMC_OCP_TXEN_R
  E10  GPIOR7_MDIO1  BI  = FM_SLT_CFG1
  E11  NTRST  BI  = JTAG_BMC_TRST_N
  E12  GPIOC5_SD1DAT3_SDA12  BI  = SMB_PEHPCPU1_STBY_LVC3_SDA
  E13  GPIOA3_TIMER4  BI  = FM_BMC_SYS_THROTTLE_R_N
  E14  GPIOG7_SGPS2I1_SALT4  BI  = FM_BIOS_SMI_ACTIVE_N
  E15  GPIOI1_SYSCK  BI  = FM_CPU1_FIVR_FAULT_LVT3_R_N
  E16  GPIOG3_SGPS1I1  BI  = FM_CPU0_SKTOCC_LVT3_N
  E17  GPIOG4_SGPS2CK_SALT1  BI  = IRQ_PCH_NIC_ALERT_N
  E18  GPIOE4_NDTR3  BI  = FP_NMI_BTN_N
  E19  GPIOG1_SGPS1LD  BI  = FM_CPU_CATERR_LVT3_N
  E20  GPIOD5_SD2DAT3  BI  = FM_BOARD_REV_ID2
  E21  GPIOD1_SD2CMD  BI  = FM_BOARD_REV_ID0
  E22  GPIOAC3_ESPID3_LAD3  BI  = LPC_LAD3_IO3_R
  F1  ADC11_GPIX3  IN  = FM_GLOBAL_RST_WARN_N_R
  F2  ADC8_GPIX0  IN  = GND
  F3  ADC4_GPIW4  IN  = A_PVNN_STBY_PCH_SENSOR
  F4  ADC0_GPIW0  IN  = A_P3V3_SCALED
  F5  ADC1_GPIW1  IN  = A_P5V_SCALED
  F6  IV11D0  POWER  = P1V15_AUX_BMC
  F7  R2VDD0  POWER  = P3V3_STBY
  F8  R2VDD1  POWER  = P3V3_STBY
  F9  RGMII1TXD0_RMII1TXD0_GPIOT2  OUT  = RMII_BMC_OCP_TXD0_R
  F10  R1VDD0  POWER  = P3V3_STBY
  F11  R1VDD1  POWER  = P3V3_STBY
  F12  PV33D0  POWER  = VCC_D_3V3
  F13  PV33D1  POWER  = VCC_D_3V3
  F14  PV33D2  POWER  = VCC_D_3V3
  F15  PV33D3  POWER  = VCC_D_3V3
  F16  GND11  POWER  = GND
  F17  GPIOE3_NRI3  BI  = FM_BMC_PWRBTN_OUT_N
  F18  GPIOE2_NDSR3  BI  = FM_PWR_BTN_R1_N
  F19  GPIOD0_SD2CLK  BI  = FM_BIOS_MRC_DEBUG_MSG_DIS_N
  F20  GPIOD2_SD2DAT0  BI  = FM_SOL_UART_CH_SEL
  F21  \gpioac5_espics#_lframe#\  BI  = LPC_LFRAME_N_CS0_R_N
  F22  \gpioac6_espialt#_lsirq#\  BI  = IRQ_LPC_SERIRQ_R
  G1  ADC13_GPIX5  IN  = H_CPU0_MEMDEF_MEMHOT_LVT3_BMC_N
  G2  ADC10_GPIX2  IN  = GND
  G3  ADC9_GPIX1  IN  = GND
  G4  ADC7_GPIW7  IN  = A_P3V_BAT_SCALED
  G5  ADC6_GPIW6  IN  = A_P5V_STBY_SCALED
  G6  GND13  POWER  = GND
  G7  IV11D7  POWER  = P1V15_AUX_BMC
  G8  IV11D8  POWER  = P1V15_AUX_BMC
  G9  IV11D9  POWER  = P1V15_AUX_BMC
  G10  IV11D1  POWER  = P1V15_AUX_BMC
  G11  IV11D2  POWER  = P1V15_AUX_BMC
  G12  IV11D3  POWER  = P1V15_AUX_BMC
  G13  IV11D4  POWER  = P1V15_AUX_BMC
  G14  IV11D5  POWER  = P1V15_AUX_BMC
  G15  IV11D6  POWER  = P1V15_AUX_BMC
  G16  PV33D4  POWER  = VCC_D_3V3
  G17  \gpiof6_txd4_lhsirq#\  BI  = FM_BATTERY_SENSE_EN_N
  G18  \gpiod6_sd2cd#\  BI  = FM_CPU_ERR0_LVT3_BMC_N
  G19  GND12  POWER  = GND
  G20  GPIOAC1_ESPID1_LAD1  BI  = LPC_LAD1_IO1_R
  G21  GPIOAC0_ESPID0_LAD0  BI  = LPC_LAD0_IO0_R
  G22  \gpioac7_espirst#_lpcrst#\  BI  = RST_BMC_LVC3_N
  H1  ADCVREFN  OUT  = P3V3_STBY_BMC_ADCVREFN
  H2  ADCVREFP  OUT  = P3V3_STBY_BMC_ADCVREFP
  H3  ADC14_GPIX6  IN  = H_CPU1_MEMGHJ_MEMHOT_LVT3_BMC_N
  H4  ADC15_GPIX7  IN  = H_CPU1_MEMKLM_MEMHOT_LVT3_BMC_N
  H5  ADC12_GPIX4  IN  = H_CPU0_MEMABC_MEMHOT_LVT3_BMC_N
  H6  GND14  POWER  = GND
  H7  VPLLAV331  POWER  = VCC_VA_3V3
  H16  IV11D10  POWER  = P1V15_AUX_BMC
  H17  PV33D5  POWER  = VCC_D_3V3
  H18  \gpiof7_rxd4_lhrst#\  BI  = FM_OCP_MEZZC_PRES_LVT3_BMC
  H19  \gpiof5_nrts4_lhframe#\  BI  = FM_OCP_MEZZB_PRES_LVT3_BMC
  H20  GPIOB7  BI  = IRQ_PVDDQ_GHJ_VRHOT_LVT3_N
  H21  \gpiob5_lpcpd#_lpcsmi#\  BI  = IRQ_BMC_PCH_SMI_LPC_N
  H22  \gpiob6_lpcpme#\  BI  = PWRGD_SYS_PWROK
  J1  ADCREXT  OUT  = PD_ADCREXT
  J2  DACB  OUT  = BMC_VGA_BLUE
  J3  DACG  OUT  = BMC_VGA_GREEN
  J4  DACR  OUT  = BMC_VGA_RED
  J5  GND22  POWER  = GND
  J6  ADCAV33  POWER  = VCC_ADCAV3V3
  J7  VPLLAV330  POWER  = VCC_VA_3V3
  J9  GND23  POWER  = GND
  J10  GND15  POWER  = GND
  J11  GND16  POWER  = GND
  J12  GND17  POWER  = GND
  J13  GND18  POWER  = GND
  J14  GND19  POWER  = GND
  J16  IV11D11  POWER  = P1V15_AUX_BMC
  J17  LPVDD0  POWER  = P3V3_STBY
  J18  GPIOF1_NDCD4_LHAD1  BI  = SPI_BMC_BT_WP0_N
  J19  GPIOF0_NCTS4_LHAD0  BI  = IRQ_PVDDQ_ABC_VRHOT_LVT3_N
  J20  GPIOB4_USBCKI  BI  = CLK_48M_USB_BMC_R
  J21  GND20  POWER  = GND
  J22  GND21  POWER  = GND
  K1  TXD5  OUT  = UART_BMC_TXD5
  K2  RXD5  IN  = UART_BMC_RXD5
  K3  ENTEST  IN  = PD_SP_ENTEST
  K4  DACRSET  UNSPEC  = A_DACRSET
  K5  DACDV33  POWER  = VCC_DACAV3V3
  K6  DACAV33  POWER  = VCC_DACAV3V3
  K7  PV33D6  POWER  = VCC_D_3V3
  K9  GND30  POWER  = GND
  K10  GND24  POWER  = GND
  K11  GND25  POWER  = GND
  K12  GND26  POWER  = GND
  K13  GND27  POWER  = GND
  K14  GND28  POWER  = GND
  K16  GND29  POWER  = GND
  K17  LPVDD1  POWER  = P3V3_STBY
  K18  GPIOB3  BI  = H_CPU0_FAST_WAKE_LVT3_N
  K19  GPIOB0  BI  = PWRGD_PCH_PWROK
  K20  PEREXT  UNSPEC  = PD_PEREXT
  K21  PEREFCLKP  IN  = CLK_100M_BMC_PE_R_DP
  K22  PEREFCLKN  IN  = CLK_100M_BMC_PE_R_DN
  L1  GPIOK2_SCL6  BI  = SMB_VR_STBY_LVC3_SCL_R
  L2  GPIOJ1_SGPMLD  BI  = SGPIO_BMC_LD_R_N
  L3  GPIOK0_SCL5  BI  = SMB_SMLINK0_STBY_LVC3_SCL_R
  L4  GPIOK1_SDA5  BI  = SMB_SMLINK0_STBY_LVC3_SDA_R
  L5  VPLLAV110  POWER  = VCC_A_1V1
  L6  VPLLAV111  POWER  = VCC_A_1V1
  L7  IV11D12  POWER  = P1V15_AUX_BMC
  L9  GND36  POWER  = GND
  L10  GND31  POWER  = GND
  L11  GND32  POWER  = GND
  L12  GND33  POWER  = GND
  L13  GND34  POWER  = GND
  L14  GND35  POWER  = GND
  L16  PEAV33  POWER  = VCC_D_3V3
  L17  PEAV11  POWER  = P1V15_AUX_BMC
  L18  GPIOB2  BI  = FM_MP_PS_FAIL_N
  L19  GPIOB1  BI  = BMC_DEBUG_EN_N
  L20  \perst#\  BI  = RST_PLTRST_BUF_N_R
  L21  PETXP  OUT  = P2E_SSB_BMC_RX_DP
  L22  PETXN  OUT  = P2E_SSB_BMC_RX_DN
  M1  GND37  POWER  = GND
  M2  GND45  POWER  = GND
  M3  GND46  POWER  = GND
  M4  GND47  POWER  = GND
  M5  GND48  POWER  = GND
  M6  GND49  POWER  = GND
  M7  GND50  POWER  = GND
  M9  GND51  POWER  = GND
  M10  GND38  POWER  = GND
  M11  GND39  POWER  = GND
  M12  GND40  POWER  = GND
  M13  GND41  POWER  = GND
  M14  GND42  POWER  = GND
  M16  GND43  POWER  = GND
  M17  GND44  POWER  = GND
  M18  GPIOY4_SCL1  BI  = SMB_LAN_STBY_LVC3_SCL_R
  M19  GPIOY5_SDA1  BI  = SMB_LAN_STBY_LVC3_SDA_R
  M20  GPIOY6_SCL2  BI  = SMB_SLOTX24_STBY_LVC3_SCL_R
  M21  PERXP  IN  = P2E_SSB_BMC_TX_C_DP
  M22  PERXN  IN  = P2E_SSB_BMC_TX_C_DN
  N1  GPIOK4_SCL7  BI  = SMB_SENSOR_BMC_STBY_LVC3_SCL
  N2  GPIOK3_SDA6  BI  = SMB_VR_STBY_LVC3_SDA_R
  N3  GPIOJ2_SGPMO  BI  = SGPIO_BMC_DOUT_R
  N4  GPIOJ3_SGPMI  BI  = SGPIO_BMC_DIN
  N5  GPIOJ4_VGAHS  BI  = BMC_VGA_HSYNC
  N6  PV33D8  POWER  = VCC_D_3V3
  N7  IV11D14  POWER  = P1V15_AUX_BMC
  N9  GND57  POWER  = GND
  N10  GND52  POWER  = GND
  N11  GND53  POWER  = GND
  N12  GND54  POWER  = GND
  N13  GND55  POWER  = GND
  N14  GND56  POWER  = GND
  N16  IV11D13  POWER  = P1V15_AUX_BMC
